# BASEBOARD_FAB2 (Tioga Pass) — schematic netlist excerpt (pin names and nets, part order shuffled) for the footprints in the layout excerpt that follows; sources: Cadence DE-HDL packaged netlist, KiCad conversion of Wiwynn_Tioga_Pass_MB.brd

R1T10  RES  1.00K 1% CHIP  pkg 0402  page 164 : A = FM_BOARD_REV_ID0 ; B = GND
CT18  CAP  1000PF 50V 10% X7R  pkg 0402LF  page 208 : A = VR_PVCCIN_CPU1_PHASE3 ; B = VR_PVCCIN_CPU1_PHASE3_RC
CT11  CAP  1000PF 50V 10% X7R  pkg 0402LF  page 227 : A = VR_PVDDQ_KLM_PH2_SW ; B = VR_PVDDQ_KLM_PH2_RC

(kicad_pcb
	(version 20260206)
	(generator "pcbnew")
	(generator_version "10.0")
	(general
		(thickness 1.6)
		(legacy_teardrops no)
	)
	(paper "A4")
	(title_block
		(title "Wiwynn_Tioga_Pass_MB.brd")
		(comment 1 "Tioga Pass / footprints 1325-1327 of 4770")
	)
	(layers
		(0 "F.Cu" signal "TOP")
		(4 "In1.Cu" signal "L2GND")
		(6 "In2.Cu" signal "L3")
		(8 "In3.Cu" signal "L4GND")
		(10 "In4.Cu" signal "L5")
		(12 "In5.Cu" signal "L6GND")
		(14 "In6.Cu" signal "L7VCC")
		(16 "In7.Cu" signal "L8VCC")
		(18 "In8.Cu" signal "L9GND")
		(20 "In9.Cu" signal "L10")
		(22 "In10.Cu" signal "L11GND")
		(24 "In11.Cu" signal "L12")
		(26 "In12.Cu" signal "L13GND")
		(2 "B.Cu" signal "BOTTOM")
		(9 "F.Adhes" user "F.Adhesive")
		(11 "B.Adhes" user "B.Adhesive")
		(13 "F.Paste" user "Package Geometry/Pastemask Top")
		(15 "B.Paste" user "Package Geometry/Pastemask Bottom")
		(5 "F.SilkS" user "Ref Des/Silkscreen Top")
		(7 "B.SilkS" user "Ref Des/Silkscreen Bottom")
		(1 "F.Mask" user "Board Geometry/Soldermask Top")
		(3 "B.Mask" user "Board Geometry/Soldermask Bottom")
		(17 "Dwgs.User" user "User.Drawings")
		(19 "Cmts.User" user "User.Comments")
		(21 "Eco1.User" user "User.Eco1")
		(23 "Eco2.User" user "User.Eco2")
		(25 "Edge.Cuts" user "Board Geometry/Outline")
		(27 "Margin" user)
		(31 "F.CrtYd" user "Package Geometry/Place Bound Top")
		(29 "B.CrtYd" user "Package Geometry/Place Bound Bottom")
		(35 "F.Fab" user "Ref Des/Assembly Top")
		(33 "B.Fab" user "Ref Des/Assembly Bottom")
	)
	(footprint ""
		(layer "F.Cu")
		(at 8.616188 -142.883128 -90)
		(property "Reference" "CT11"
			(at -0.8382 -0.67818 270)
			(unlocked yes)
			(layer "F.SilkS")
			(effects
				(font
					(size 0.4064 0.254)
					(thickness 0.1524)
				)
				(justify left)
			)
		)
		(property "Value" ""
			(at 0 0 270)
			(layer "F.Fab")
			(effects
				(font
					(size 1.27 1.27)
				)
			)
		)
		(duplicate_pad_numbers_are_jumpers no)
		(fp_poly
			(pts
				(xy 0.3048 -0.1016) (xy 0.3048 0.9906) (xy -0.3048 0.9906) (xy -0.3048 -0.1016)
			)
			(stroke
				(width 0)
				(type default)
			)
			(fill no)
			(layer "F.CrtYd")
		)
		(fp_line
			(start -0.3048 0.9906)
			(end 0.3048 0.9906)
			(stroke
				(width 0.1)
				(type default)
			)
			(layer "F.Fab")
		)
		(fp_line
			(start 0.3048 0.9906)
			(end 0.3048 -0.1016)
			(stroke
				(width 0.1)
				(type default)
			)
			(layer "F.Fab")
		)
		(fp_line
			(start -0.3048 -0.1016)
			(end -0.3048 0.9906)
			(stroke
				(width 0.1)
				(type default)
			)
			(layer "F.Fab")
		)
		(fp_line
			(start 0.3048 -0.1016)
			(end -0.3048 -0.1016)
			(stroke
				(width 0.1)
				(type default)
			)
			(layer "F.Fab")
		)
		(pad "1" smd rect
			(at 0 0 270)
			(size 0.508 0.508)
			(layers "F.Cu" "F.Mask" "F.Paste")
			(net "VR_PVDDQ_KLM_PH2_SW")
		)
		(pad "2" smd rect
			(at 0 0.889 270)
			(size 0.508 0.508)
			(layers "F.Cu" "F.Mask" "F.Paste")
			(net "VR_PVDDQ_KLM_PH2_RC")
		)
		(zone
			(layer "F.Cu")
			(hatch none 0.5)
			(connect_pads
				(clearance 0)
			)
			(min_thickness 0.25)
			(keepout
				(tracks not_allowed)
				(vias allowed)
				(pads allowed)
				(copperpour not_allowed)
				(footprints allowed)
			)
			(placement
				(enabled no)
				(sheetname "")
			)
			(fill
				(thermal_gap 0.5)
				(thermal_bridge_width 0.5)
				(island_removal_mode 0)
			)
			(polygon
				(pts
					(xy 7.981188 -143.137128) (xy 7.981188 -142.629128) (xy 8.362188 -142.629128) (xy 8.362188 -143.137128)
				)
			)
		)
		(zone
			(layer "F.Cu")
			(hatch none 0.5)
			(connect_pads
				(clearance 0)
			)
			(min_thickness 0.25)
			(keepout
				(tracks allowed)
				(vias not_allowed)
				(pads allowed)
				(copperpour not_allowed)
				(footprints allowed)
			)
			(placement
				(enabled no)
				(sheetname "")
			)
			(fill
				(thermal_gap 0.5)
				(thermal_bridge_width 0.5)
				(island_removal_mode 0)
			)
			(polygon
				(pts
					(xy 8.362188 -143.137128) (xy 8.362188 -142.629128) (xy 7.981188 -142.629128) (xy 7.981188 -143.137128)
				)
			)
		)
	)
	(footprint ""
		(layer "F.Cu")
		(at 408.923236 -47.825914 180)
		(property "Reference" "R1T10"
			(at 0 0 180)
			(layer "F.SilkS")
			(hide yes)
			(effects
				(font
					(size 1.27 1.27)
				)
			)
		)
		(property "Value" ""
			(at 0 0 180)
			(layer "F.Fab")
			(effects
				(font
					(size 1.27 1.27)
				)
			)
		)
		(duplicate_pad_numbers_are_jumpers no)
		(fp_poly
			(pts
				(xy -0.2794 -0.1016) (xy 0.2794 -0.1016) (xy 0.2794 0.9906) (xy -0.2794 0.9906)
			)
			(stroke
				(width 0)
				(type default)
			)
			(fill no)
			(layer "F.CrtYd")
		)
		(fp_line
			(start 0.2794 0.9906)
			(end 0.2794 -0.1016)
			(stroke
				(width 0.1)
				(type default)
			)
			(layer "F.Fab")
		)
		(fp_line
			(start 0.2794 -0.1016)
			(end -0.2794 -0.1016)
			(stroke
				(width 0.1)
				(type default)
			)
			(layer "F.Fab")
		)
		(fp_line
			(start -0.2794 0.9906)
			(end 0.2794 0.9906)
			(stroke
				(width 0.1)
				(type default)
			)
			(layer "F.Fab")
		)
		(fp_line
			(start -0.2794 -0.1016)
			(end -0.2794 0.9906)
			(stroke
				(width 0.1)
				(type default)
			)
			(layer "F.Fab")
		)
		(pad "1" smd rect
			(at 0 0 180)
			(size 0.508 0.508)
			(layers "F.Cu" "F.Mask" "F.Paste")
			(net "FM_BOARD_REV_ID0")
		)
		(pad "2" smd rect
			(at 0 0.889 180)
			(size 0.508 0.508)
			(layers "F.Cu" "F.Mask" "F.Paste")
			(net "GND")
		)
	)
	(footprint ""
		(layer "F.Cu")
		(at 39.8018 -69.3166 -90)
		(property "Reference" "CT18"
			(at -0.8382 -0.67818 270)
			(unlocked yes)
			(layer "F.SilkS")
			(effects
				(font
					(size 0.4064 0.254)
					(thickness 0.1524)
				)
				(justify left)
			)
		)
		(property "Value" ""
			(at 0 0 270)
			(layer "F.Fab")
			(effects
				(font
					(size 1.27 1.27)
				)
			)
		)
		(duplicate_pad_numbers_are_jumpers no)
		(fp_poly
			(pts
				(xy 0.3048 -0.1016) (xy 0.3048 0.9906) (xy -0.3048 0.9906) (xy -0.3048 -0.1016)
			)
			(stroke
				(width 0)
				(type default)
			)
			(fill no)
			(layer "F.CrtYd")
		)
		(fp_line
			(start -0.3048 0.9906)
			(end 0.3048 0.9906)
			(stroke
				(width 0.1)
				(type default)
			)
			(layer "F.Fab")
		)
		(fp_line
			(start 0.3048 0.9906)
			(end 0.3048 -0.1016)
			(stroke
				(width 0.1)
				(type default)
			)
			(layer "F.Fab")
		)
		(fp_line
			(start -0.3048 -0.1016)
			(end -0.3048 0.9906)
			(stroke
				(width 0.1)
				(type default)
			)
			(layer "F.Fab")
		)
		(fp_line
			(start 0.3048 -0.1016)
			(end -0.3048 -0.1016)
			(stroke
				(width 0.1)
				(type default)
			)
			(layer "F.Fab")
		)
		(pad "1" smd rect
			(at 0 0 270)
			(size 0.508 0.508)
			(layers "F.Cu" "F.Mask" "F.Paste")
			(net "VR_PVCCIN_CPU1_PHASE3")
		)
		(pad "2" smd rect
			(at 0 0.889 270)
			(size 0.508 0.508)
			(layers "F.Cu" "F.Mask" "F.Paste")
			(net "VR_PVCCIN_CPU1_PHASE3_RC")
		)
		(zone
			(layer "F.Cu")
			(hatch none 0.5)
			(connect_pads
				(clearance 0)
			)
			(min_thickness 0.25)
			(keepout
				(tracks not_allowed)
				(vias allowed)
				(pads allowed)
				(copperpour not_allowed)
				(footprints allowed)
			)
			(placement
				(enabled no)
				(sheetname "")
			)
			(fill
				(thermal_gap 0.5)
				(thermal_bridge_width 0.5)
				(island_removal_mode 0)
			)
			(polygon
				(pts
					(xy 39.1668 -69.5706) (xy 39.1668 -69.0626) (xy 39.5478 -69.0626) (xy 39.5478 -69.5706)
				)
			)
		)
		(zone
			(layer "F.Cu")
			(hatch none 0.5)
			(connect_pads
				(clearance 0)
			)
			(min_thickness 0.25)
			(keepout
				(tracks allowed)
				(vias not_allowed)
				(pads allowed)
				(copperpour not_allowed)
				(footprints allowed)
			)
			(placement
				(enabled no)
				(sheetname "")
			)
			(fill
				(thermal_gap 0.5)
				(thermal_bridge_width 0.5)
				(island_removal_mode 0)
			)
			(polygon
				(pts
					(xy 39.5478 -69.5706) (xy 39.5478 -69.0626) (xy 39.1668 -69.0626) (xy 39.1668 -69.5706)
				)
			)
		)
	)
)
